(kicad_pcb
	(version 20260206)
	(generator "pcbnew")
	(generator_version "10.0")
	(general
		(thickness 1.6)
		(legacy_teardrops no)
	)
	(paper "A4")
	(title_block
		(title "03242023_DA0F0TMBIJ0_F0T_Motherboard_J_brd_V01_OCP.brd")
		(comment 1 "Grand Teton / footprints 2907-2910 of 6105")
	)
	(layers
		(0 "F.Cu" signal "TOP")
		(4 "In1.Cu" signal "GND")
		(6 "In2.Cu" signal "IN1")
		(8 "In3.Cu" signal "GND1")
		(10 "In4.Cu" signal "IN2")
		(12 "In5.Cu" signal "GND2")
		(14 "In6.Cu" signal "IN3")
		(16 "In7.Cu" signal "GND3")
		(18 "In8.Cu" signal "VCC")
		(20 "In9.Cu" signal "VCC1")
		(22 "In10.Cu" signal "GND4")
		(24 "In11.Cu" signal "IN4")
		(26 "In12.Cu" signal "GND5")
		(28 "In13.Cu" signal "IN5")
		(30 "In14.Cu" signal "GND6")
		(32 "In15.Cu" signal "IN6")
		(34 "In16.Cu" signal "GND7")
		(2 "B.Cu" signal "BOTTOM")
		(9 "F.Adhes" user "F.Adhesive")
		(11 "B.Adhes" user "B.Adhesive")
		(13 "F.Paste" user "Package Geometry/Pastemask Top")
		(15 "B.Paste" user "Package Geometry/Pastemask Bottom")
		(5 "F.SilkS" user "Ref Des/Silkscreen Top")
		(7 "B.SilkS" user "Ref Des/Silkscreen Bottom")
		(1 "F.Mask" user "Board Geometry/Soldermask Top")
		(3 "B.Mask" user "Board Geometry/Soldermask Bottom")
		(17 "Dwgs.User" user "User.Drawings")
		(19 "Cmts.User" user "User.Comments")
		(21 "Eco1.User" user "User.Eco1")
		(23 "Eco2.User" user "User.Eco2")
		(25 "Edge.Cuts" user "Board Geometry/Outline")
		(27 "Margin" user)
		(31 "F.CrtYd" user "Package Geometry/Place Bound Top")
		(29 "B.CrtYd" user "Package Geometry/Place Bound Bottom")
		(35 "F.Fab" user "Ref Des/Assembly Top")
		(33 "B.Fab" user "Ref Des/Assembly Bottom")
	)
	(footprint ""
		(layer "F.Cu")
		(at 298.474384 -362.7755)
		(property "Reference" "PU70_P0_2"
			(at 8.245856 -3.740658 0)
			(unlocked yes)
			(layer "F.SilkS")
			(effects
				(font
					(size 0.7874 0.5842)
					(thickness 0.1524)
				)
				(justify left)
			)
		)
		(property "Value" ""
			(at 0 0 0)
			(layer "F.Fab")
			(effects
				(font
					(size 1.27 1.27)
				)
			)
		)
		(duplicate_pad_numbers_are_jumpers no)
		(fp_line
			(start -2.500122 -2.999994)
			(end -2.24409 -2.999994)
			(stroke
				(width 0.1524)
				(type default)
			)
			(layer "F.SilkS")
		)
		(fp_line
			(start -2.500122 -2.529078)
			(end -2.500122 -2.999994)
			(stroke
				(width 0.1524)
				(type default)
			)
			(layer "F.SilkS")
		)
		(fp_line
			(start -2.500122 0.6604)
			(end -2.500122 0.229108)
			(stroke
				(width 0.1524)
				(type default)
			)
			(layer "F.SilkS")
		)
		(fp_line
			(start -2.500122 2.999994)
			(end -2.500122 2.339594)
			(stroke
				(width 0.1524)
				(type default)
			)
			(layer "F.SilkS")
		)
		(fp_line
			(start -2.2987 2.999994)
			(end -2.500122 2.999994)
			(stroke
				(width 0.1524)
				(type default)
			)
			(layer "F.SilkS")
		)
		(fp_line
			(start 2.31394 -2.999994)
			(end 2.500122 -2.999994)
			(stroke
				(width 0.1524)
				(type default)
			)
			(layer "F.SilkS")
		)
		(fp_line
			(start 2.500122 -2.999994)
			(end 2.500122 -2.44348)
			(stroke
				(width 0.1524)
				(type default)
			)
			(layer "F.SilkS")
		)
		(fp_line
			(start 2.500122 2.339594)
			(end 2.500122 2.999994)
			(stroke
				(width 0.1524)
				(type default)
			)
			(layer "F.SilkS")
		)
		(fp_line
			(start 2.500122 2.999994)
			(end 2.2987 2.999994)
			(stroke
				(width 0.1524)
				(type default)
			)
			(layer "F.SilkS")
		)
		(fp_poly
			(pts
				(xy -2.164334 -3.650996) (xy -2.672334 -2.634996) (xy -3.180334 -3.650996)
			)
			(stroke
				(width 0)
				(type default)
			)
			(fill yes)
			(layer "F.SilkS")
		)
		(fp_line
			(start -2.500122 -2.999994)
			(end 2.500122 -2.999994)
			(stroke
				(width 0.1)
				(type default)
			)
			(layer "F.Fab")
		)
		(fp_line
			(start -2.500122 2.999994)
			(end -2.500122 -2.999994)
			(stroke
				(width 0.1)
				(type default)
			)
			(layer "F.Fab")
		)
		(fp_line
			(start 2.500122 -2.999994)
			(end 2.500122 2.999994)
			(stroke
				(width 0.1)
				(type default)
			)
			(layer "F.Fab")
		)
		(fp_line
			(start 2.500122 2.999994)
			(end -2.500122 2.999994)
			(stroke
				(width 0.1)
				(type default)
			)
			(layer "F.Fab")
		)
		(fp_poly
			(pts
				(xy -4.218432 -2.783078) (xy -4.218432 -1.767078) (xy -3.202432 -2.275078)
			)
			(stroke
				(width 0)
				(type default)
			)
			(fill yes)
			(layer "F.Fab")
		)
		(pad "1" smd rect
			(at -2.400046 -2.275078 90)
			(size 0.2286 0.6096)
			(layers "F.Cu" "F.Mask" "F.Paste")
			(net "PVCCFA_EHV_FIVRA_CPU0_VOS2")
		)
		(pad "2" smd rect
			(at -2.400046 -1.82499 90)
			(size 0.2286 0.6096)
			(layers "F.Cu" "F.Mask" "F.Paste")
			(net "GND")
		)
		(pad "3" smd rect
			(at -2.400046 -1.374902 90)
			(size 0.2286 0.6096)
			(layers "F.Cu" "F.Mask" "F.Paste")
			(net "PVCCFA_EHV_FIVRA_CPU0_VDD2")
		)
		(pad "4" smd rect
			(at -2.400046 -0.925068 90)
			(size 0.2286 0.6096)
			(layers "F.Cu" "F.Mask" "F.Paste")
			(net "PVCCFA_EHV_FIVRA_CPU0_PVCC2")
		)
		(pad "5" smd rect
			(at -2.400046 -0.47498 90)
			(size 0.2286 0.6096)
			(layers "F.Cu" "F.Mask" "F.Paste")
			(net "GND")
		)
		(pad "6" smd rect
			(at -2.400046 -0.024892 90)
			(size 0.2286 0.6096)
			(layers "F.Cu" "F.Mask" "F.Paste")
			(net "Net_8514")
		)
		(pad "7_9-20_24" smd circle
			(at 0 1.150112 90)
			(size 0 0)
			(layers "F.Cu" "F.Mask" "F.Paste")
			(net "GND")
		)
		(pad "10_19" smd rect
			(at 0 2.899918 90)
			(size 0.6096 4.318)
			(layers "F.Cu" "F.Mask" "F.Paste")
			(net "SW_PVCCFA_EHV_FIVRA_CPU0_SW2")
		)
		(pad "25_29" smd rect
			(at 1.549908 -1.279906 270)
			(size 2.0574 2.3114)
			(layers "F.Cu" "F.Mask" "F.Paste")
			(net "SW_P12V_PVCCFA_EHV_FIVRA_CPU0_L")
		)
		(pad "30" smd rect
			(at 2.05994 -2.899918)
			(size 0.2286 0.6096)
			(layers "F.Cu" "F.Mask" "F.Paste")
			(net "SW_P12V_PVCCFA_EHV_FIVRA_CPU0_L")
		)
		(pad "31" smd rect
			(at 1.610106 -2.899918)
			(size 0.2286 0.6096)
			(layers "F.Cu" "F.Mask" "F.Paste")
			(net "Net_8515")
		)
		(pad "32" smd rect
			(at 1.160018 -2.899918)
			(size 0.2286 0.6096)
			(layers "F.Cu" "F.Mask" "F.Paste")
			(net "SW_PVCCFA_EHV_FIVRA_CPU0_BOOTR2")
		)
		(pad "33" smd rect
			(at 0.70993 -2.899918)
			(size 0.2286 0.6096)
			(layers "F.Cu" "F.Mask" "F.Paste")
			(net "SW_PVCCFA_EHV_FIVRA_CPU0_BOOT2")
		)
		(pad "34" smd rect
			(at 0.260096 -2.899918)
			(size 0.2286 0.6096)
			(layers "F.Cu" "F.Mask" "F.Paste")
			(net "PVCCFA_EHV_FIVRA_CPU0_PWM2")
		)
		(pad "35" smd rect
			(at -0.189992 -2.899918)
			(size 0.2286 0.6096)
			(layers "F.Cu" "F.Mask" "F.Paste")
			(net "PVCCFA_EHV_FIVRA_CPU0_VDD2")
		)
		(pad "36" smd rect
			(at -0.64008 -2.899918)
			(size 0.2286 0.6096)
			(layers "F.Cu" "F.Mask" "F.Paste")
			(net "PVCCFA_EHV_FIVRA_CPU0_BTSEN")
		)
		(pad "37" smd rect
			(at -1.089914 -2.899918)
			(size 0.2286 0.6096)
			(layers "F.Cu" "F.Mask" "F.Paste")
			(net "PVCCFA_EHV_FIVRA_CPU0_LSET2")
		)
		(pad "38" smd rect
			(at -1.540002 -2.899918)
			(size 0.2286 0.6096)
			(layers "F.Cu" "F.Mask" "F.Paste")
			(net "PVCCFA_EHV_FIVRA_CPU0_IMON2")
		)
		(pad "39" smd rect
			(at -1.99009 -2.899918)
			(size 0.2286 0.6096)
			(layers "F.Cu" "F.Mask" "F.Paste")
			(net "PVCCIN_CPU0_VREF")
		)
		(pad "40" smd rect
			(at -0.87503 -1.27508)
			(size 1.7526 1.9558)
			(layers "F.Cu" "F.Mask" "F.Paste")
			(net "GND")
		)
		(pad "41" smd rect
			(at -1.525016 0.249936 270)
			(size 0.3048 0.4572)
			(layers "F.Cu" "F.Mask" "F.Paste")
			(net "Net_8513")
		)
		(zone
			(layer "F.Cu")
			(hatch none 0.5)
			(connect_pads
				(clearance 0)
			)
			(min_thickness 0.25)
			(keepout
				(tracks not_allowed)
				(vias allowed)
				(pads allowed)
				(copperpour not_allowed)
				(footprints allowed)
			)
			(placement
				(enabled no)
				(sheetname "")
			)
			(fill
				(thermal_gap 0.5)
				(thermal_bridge_width 0.5)
				(island_removal_mode 0)
			)
			(polygon
				(pts
					(xy 295.974262 -359.775506) (xy 295.974262 -360.512868) (xy 300.974506 -360.512868) (xy 300.974506 -359.775506)
					(xy 300.684184 -359.775506) (xy 300.684184 -360.231182) (xy 296.264584 -360.231182) (xy 296.264584 -359.775506)
				)
			)
		)
		(zone
			(layer "F.Cu")
			(hatch none 0.5)
			(connect_pads
				(clearance 0)
			)
			(min_thickness 0.25)
			(keepout
				(tracks not_allowed)
				(vias allowed)
				(pads allowed)
				(copperpour not_allowed)
				(footprints allowed)
			)
			(placement
				(enabled no)
				(sheetname "")
			)
			(fill
				(thermal_gap 0.5)
				(thermal_bridge_width 0.5)
				(island_removal_mode 0)
			)
			(polygon
				(pts
					(xy 296.73296 -363.02188) (xy 297.44924 -363.02188) (xy 297.44924 -362.699808) (xy 297.523662 -362.699808)
					(xy 297.523662 -362.075222) (xy 297.47464 -362.0262) (xy 295.974262 -362.0262) (xy 295.974262 -362.482892)
					(xy 296.669968 -362.482892) (xy 296.669968 -362.322364) (xy 297.228768 -362.322364) (xy 297.228768 -362.728764)
					(xy 296.669968 -362.728764) (xy 296.669968 -362.508292) (xy 295.974262 -362.508292) (xy 295.974262 -362.635292)
					(xy 296.429938 -362.635292) (xy 296.429938 -362.994448) (xy 296.73296 -362.994448)
				)
			)
		)
	)
	(footprint ""
		(layer "F.Cu")
		(at 434.86832 -126.850648 180)
		(property "Reference" "PC627"
			(at 0 0 180)
			(layer "F.SilkS")
			(hide yes)
			(effects
				(font
					(size 1.27 1.27)
				)
			)
		)
		(property "Value" ""
			(at 0 0 180)
			(layer "F.Fab")
			(effects
				(font
					(size 1.27 1.27)
				)
			)
		)
		(duplicate_pad_numbers_are_jumpers no)
		(fp_line
			(start 0.7874 0.4064)
			(end -0.7874 0.4064)
			(stroke
				(width 0.1524)
				(type default)
			)
			(layer "F.SilkS")
		)
		(fp_line
			(start 0.7874 -0.4064)
			(end 0.7874 0.4064)
			(stroke
				(width 0.1524)
				(type default)
			)
			(layer "F.SilkS")
		)
		(fp_line
			(start -0.7874 0.4064)
			(end -0.7874 -0.4064)
			(stroke
				(width 0.1524)
				(type default)
			)
			(layer "F.SilkS")
		)
		(fp_line
			(start -0.7874 -0.4064)
			(end 0.7874 -0.4064)
			(stroke
				(width 0.1524)
				(type default)
			)
			(layer "F.SilkS")
		)
		(fp_line
			(start 0.67945 0.3048)
			(end 0.120396 0.3048)
			(stroke
				(width 0.1)
				(type default)
			)
			(layer "F.Fab")
		)
		(fp_line
			(start 0.67945 -0.3048)
			(end 0.67945 0.3048)
			(stroke
				(width 0.1)
				(type default)
			)
			(layer "F.Fab")
		)
		(fp_line
			(start 0.12065 -0.2794)
			(end 0.12065 -0.3048)
			(stroke
				(width 0.1)
				(type default)
			)
			(layer "F.Fab")
		)
		(fp_line
			(start 0.12065 -0.3048)
			(end 0.67945 -0.3048)
			(stroke
				(width 0.1)
				(type default)
			)
			(layer "F.Fab")
		)
		(fp_line
			(start 0.120396 0.3048)
			(end 0.120396 0.2794)
			(stroke
				(width 0.1)
				(type default)
			)
			(layer "F.Fab")
		)
		(fp_line
			(start 0.120396 0.2794)
			(end -0.12065 0.2794)
			(stroke
				(width 0.1)
				(type default)
			)
			(layer "F.Fab")
		)
		(fp_line
			(start -0.12065 0.3048)
			(end -0.67945 0.3048)
			(stroke
				(width 0.1)
				(type default)
			)
			(layer "F.Fab")
		)
		(fp_line
			(start -0.12065 0.2794)
			(end -0.12065 0.3048)
			(stroke
				(width 0.1)
				(type default)
			)
			(layer "F.Fab")
		)
		(fp_line
			(start -0.12065 -0.2794)
			(end 0.12065 -0.2794)
			(stroke
				(width 0.1)
				(type default)
			)
			(layer "F.Fab")
		)
		(fp_line
			(start -0.12065 -0.305054)
			(end -0.12065 -0.2794)
			(stroke
				(width 0.1)
				(type default)
			)
			(layer "F.Fab")
		)
		(fp_line
			(start -0.67945 0.3048)
			(end -0.67945 -0.305054)
			(stroke
				(width 0.1)
				(type default)
			)
			(layer "F.Fab")
		)
		(fp_line
			(start -0.67945 -0.305054)
			(end -0.12065 -0.305054)
			(stroke
				(width 0.1)
				(type default)
			)
			(layer "F.Fab")
		)
		(pad "1" smd circle
			(at -0.40005 0 180)
			(size 0 0)
			(layers "F.Cu" "F.Mask" "F.Paste")
			(net "SH_PVCCD_HV_CPU0_R")
		)
		(pad "2" smd circle
			(at 0.40005 0 180)
			(size 0 0)
			(layers "F.Cu" "F.Mask" "F.Paste")
			(net "VSENSE_PVCCD_HV_CPU0_DN")
		)
	)
	(footprint ""
		(layer "F.Cu")
		(at 435.42712 -395.87678)
		(property "Reference" "ME28"
			(at 0 0 0)
			(layer "F.SilkS")
			(hide yes)
			(effects
				(font
					(size 1.27 1.27)
				)
			)
		)
		(property "Value" ""
			(at 0 0 0)
			(layer "F.Fab")
			(effects
				(font
					(size 1.27 1.27)
				)
			)
		)
		(duplicate_pad_numbers_are_jumpers no)
		(fp_line
			(start 0 -10.500106)
			(end 1.524 -10.500106)
			(stroke
				(width 0.1524)
				(type default)
			)
			(layer "F.SilkS")
		)
		(fp_line
			(start 0 -8.976106)
			(end 0 -10.500106)
			(stroke
				(width 0.1524)
				(type default)
			)
			(layer "F.SilkS")
		)
		(fp_line
			(start 0 0)
			(end 0 -1.524)
			(stroke
				(width 0.1524)
				(type default)
			)
			(layer "F.SilkS")
		)
		(fp_line
			(start 1.524 0)
			(end 0 0)
			(stroke
				(width 0.1524)
				(type default)
			)
			(layer "F.SilkS")
		)
		(fp_line
			(start 8.976106 0)
			(end 10.500106 0)
			(stroke
				(width 0.1524)
				(type default)
			)
			(layer "F.SilkS")
		)
		(fp_line
			(start 10.500106 -10.500106)
			(end 8.976106 -10.500106)
			(stroke
				(width 0.1524)
				(type default)
			)
			(layer "F.SilkS")
		)
		(fp_line
			(start 10.500106 -8.976106)
			(end 10.500106 -10.500106)
			(stroke
				(width 0.1524)
				(type default)
			)
			(layer "F.SilkS")
		)
		(fp_line
			(start 10.500106 0)
			(end 10.500106 -1.524)
			(stroke
				(width 0.1524)
				(type default)
			)
			(layer "F.SilkS")
		)
		(fp_text user "BIOS"
			(at 1.681226 -8.494776 0)
			(unlocked yes)
			(layer "F.SilkS")
			(effects
				(font
					(size 1.905 1.4224)
					(thickness 0.1524)
				)
				(justify left)
			)
		)
		(fp_text user "BMC"
			(at 2.303526 -1.865376 0)
			(unlocked yes)
			(layer "F.SilkS")
			(effects
				(font
					(size 1.905 1.4224)
					(thickness 0.1524)
				)
				(justify left)
			)
		)
		(fp_text user "&"
			(at 4.183126 -5.624576 0)
			(unlocked yes)
			(layer "F.SilkS")
			(effects
				(font
					(size 1.905 1.4224)
					(thickness 0.1524)
				)
				(justify left)
			)
		)
		(zone
			(layer "F.Cu")
			(hatch none 0.5)
			(connect_pads
				(clearance 0)
			)
			(min_thickness 0.25)
			(keepout
				(tracks not_allowed)
				(vias allowed)
				(pads allowed)
				(copperpour not_allowed)
				(footprints allowed)
			)
			(placement
				(enabled no)
				(sheetname "")
			)
			(fill
				(thermal_gap 0.5)
				(thermal_bridge_width 0.5)
				(island_removal_mode 0)
			)
			(polygon
				(pts
					(xy 435.42712 -395.87678) (xy 445.927226 -395.87678) (xy 445.927226 -406.376886) (xy 435.42712 -406.376886)
				)
			)
		)
	)
	(footprint ""
		(layer "F.Cu")
		(at 124.672344 -77.571092)
		(property "Reference" "R1813"
			(at 0 0 0)
			(layer "F.SilkS")
			(hide yes)
			(effects
				(font
					(size 1.27 1.27)
				)
			)
		)
		(property "Value" ""
			(at 0 0 0)
			(layer "F.Fab")
			(effects
				(font
					(size 1.27 1.27)
				)
			)
		)
		(duplicate_pad_numbers_are_jumpers no)
		(fp_line
			(start -0.7874 -0.4064)
			(end 0.7874 -0.4064)
			(stroke
				(width 0.1524)
				(type default)
			)
			(layer "F.SilkS")
		)
		(fp_line
			(start -0.7874 0.4064)
			(end -0.7874 -0.4064)
			(stroke
				(width 0.1524)
				(type default)
			)
			(layer "F.SilkS")
		)
		(fp_line
			(start 0.7874 -0.4064)
			(end 0.7874 0.4064)
			(stroke
				(width 0.1524)
				(type default)
			)
			(layer "F.SilkS")
		)
		(fp_line
			(start 0.7874 0.4064)
			(end -0.7874 0.4064)
			(stroke
				(width 0.1524)
				(type default)
			)
			(layer "F.SilkS")
		)
		(fp_line
			(start -0.67945 -0.305054)
			(end -0.12065 -0.305054)
			(stroke
				(width 0.1)
				(type default)
			)
			(layer "F.Fab")
		)
		(fp_line
			(start -0.67945 0.3048)
			(end -0.67945 -0.305054)
			(stroke
				(width 0.1)
				(type default)
			)
			(layer "F.Fab")
		)
		(fp_line
			(start -0.12065 -0.305054)
			(end -0.12065 -0.2794)
			(stroke
				(width 0.1)
				(type default)
			)
			(layer "F.Fab")
		)
		(fp_line
			(start -0.12065 -0.2794)
			(end 0.12065 -0.2794)
			(stroke
				(width 0.1)
				(type default)
			)
			(layer "F.Fab")
		)
		(fp_line
			(start -0.12065 0.2794)
			(end -0.12065 0.3048)
			(stroke
				(width 0.1)
				(type default)
			)
			(layer "F.Fab")
		)
		(fp_line
			(start -0.12065 0.3048)
			(end -0.67945 0.3048)
			(stroke
				(width 0.1)
				(type default)
			)
			(layer "F.Fab")
		)
		(fp_line
			(start 0.120396 0.2794)
			(end -0.12065 0.2794)
			(stroke
				(width 0.1)
				(type default)
			)
			(layer "F.Fab")
		)
		(fp_line
			(start 0.120396 0.3048)
			(end 0.120396 0.2794)
			(stroke
				(width 0.1)
				(type default)
			)
			(layer "F.Fab")
		)
		(fp_line
			(start 0.12065 -0.3048)
			(end 0.67945 -0.3048)
			(stroke
				(width 0.1)
				(type default)
			)
			(layer "F.Fab")
		)
		(fp_line
			(start 0.12065 -0.2794)
			(end 0.12065 -0.3048)
			(stroke
				(width 0.1)
				(type default)
			)
			(layer "F.Fab")
		)
		(fp_line
			(start 0.67945 -0.3048)
			(end 0.67945 0.3048)
			(stroke
				(width 0.1)
				(type default)
			)
			(layer "F.Fab")
		)
		(fp_line
			(start 0.67945 0.3048)
			(end 0.120396 0.3048)
			(stroke
				(width 0.1)
				(type default)
			)
			(layer "F.Fab")
		)
		(pad "1" smd circle
			(at -0.40005 0)
			(size 0 0)
			(layers "F.Cu" "F.Mask" "F.Paste")
			(net "P3V3_AUX")
		)
		(pad "2" smd circle
			(at 0.40005 0)
			(size 0 0)
			(layers "F.Cu" "F.Mask" "F.Paste")
			(net "FM_JTAG_BMC_MUX_SEL")
		)
	)
)
